FILE_TYPE = CONNECTIVITY;
{Allegro Design Entry HDL 16.6-p007 (v16-6-112F) 10/10/2012}
"PAGE_NUMBER" = 104;
0"NC";
1"P3V3\g";
2"GND\g";
3"GND\g";
4"GND\g";
5"P3V3\g";
6"GND\g";
7"CLK_156M_OSC_BRD_CPU1_DN";
8"CLK_156M_OSC_BRD_CPU0_DP";
9"FM_CPU0_VRM_OSC_EN";
10"FM_CPU0_VRM_322M_156M_OSC_EN";
11"FM_CPU1_STL_BRD_OSC_EN";
12"FM_CPU1_VRM_OSC_EN";
13"FM_CPU1_VRM_322M_156M_OSC_EN";
14"CLK_156M_OSC_CPU1_HFI_DP";
15"CLK_322M_OSC_CPU1_RC_DP";
16"FM_CPU0_STL_BRD_OSC_EN";
17"FM_156M_CPU0_BRD_OSC_EN";
18"CLK_322M_OSC_CPU0_RC_DN";
19"CLK_156M_OSC_CPU0_HFI_DP";
20"CLK_322M_OSC_CPU0_RC_DP";
21"CLK_156M_OSC_CPU1_HFI_DN";
22"CLK_322M_OSC_CPU1_RC_DN";
23"CLK_322M_156M_CPU0_OSC_VRM_DP";
24"CLK_322M_156M_CPU0_OSC_VRM_DN";
25"CLK_156M_OSC_CPU0_HFI_DN";
26"CLK_156M_OSC_BRD_CPU1_DN";
27"CLK_156M_OSC_BRD_CPU0_DP";
28"CLK_156M_OSC_BRD_CPU0_DN";
29"CLK_322M_156M_CPU1_OSC_VRM_DN";
30"CLK_322M_156M_CPU1_OSC_VRM_DP";
31"NC_CLK_156M_CPU0_OSC";
32"NC_CLK_156M_CPU1_OSC";
33"FM_CPU1_STL_BRD_OSC_EN";
34"FM_CPU0_STL_BRD_OSC_EN";
35"CLK_156M_OSC_BRD_CPU1_DP";
36"FM_156M_CPU1_BRD_OSC_EN";
37"CLK_156M_OSC_BRD_CPU0_DN";
38"CLK_156M_OSC_BRD_CPU1_DP";
%"RES"
"1","(550,1800)","0","mstr_discrete","I103";
;
CDS_SEC"1"
VALUE"0.0"
TOLERANCE"5%"
PACK_TYPE"0402"
WATTAGE"1/16W"
PART_NUMBER"G21497-005"
MATERIAL"CHIP"
LOCATION"R7D39"
CDS_LIB"mstr_discrete"
SEC_TYPE"0402"
SEC"1"
ROOM"CLOCK_CPU1_OSC"
NO_XNET_CONNECTION"1"
CDS_LOCATION"R7D39";
"B"
$PN"2"10;
"A"
$PN"1"9;
%"RES"
"1","(550,1100)","0","mstr_discrete","I104";
;
CDS_SEC"1"
LOCATION"R7D37"
VALUE"0.0"
TOLERANCE"5%"
MATERIAL"CHIP"
PACK_TYPE"0402"
WATTAGE"1/16W"
PART_NUMBER"G21497-005"
CDS_LIB"mstr_discrete"
SEC_TYPE"0402"
SEC"1"
ROOM"CLOCK_CPU1_OSC"
NO_XNET_CONNECTION"1"
CDS_LOCATION"R7D37";
"B"
$PN"2"13;
"A"
$PN"1"12;
%"P3V3"
"1","(-3975,5350)","0","mstr_symbols","I24";
;
HDL_POWER"P3V3"
BODY_TYPE"PLUMBING"
VOLTAGE"3.3V"
CDS_LIB"mstr_symbols"
SIZE"1B";
"G\NAC"1;
%"CAP_A"
"1","(-4250,5100)","0","dev_discrete","I25";
;
TOLERANCE"10%"
MATERIAL"X7R"
VOLTAGE"16V"
LOCATION"C6F1"
VALUE"0.1UF"
PACK_TYPE"0402V"
PART_NUMBER"A36096-030"
CDS_LIB"dev_discrete"
ROOM"CLOCK_CPU0_OSC"
CDS_SEC"1"
SEC_TYPE"0402V"
SEC"1"
CDS_LOCATION"C6F1";
"B"
$PN"2"3;
"A"
$PN"1"1;
%"GND"
"1","(-2725,4550)","0","mstr_symbols","I26";
;
HDL_POWER"GND"
VOLTAGE"0.0V"
CDS_LIB"mstr_symbols"
BODY_TYPE"PLUMBING"
SIZE"1B";
"A\NAC"2;
%"GND"
"1","(-4250,4900)","0","mstr_symbols","I27";
;
SIZE"1B"
BODY_TYPE"PLUMBING"
VOLTAGE"0.0V"
CDS_LIB"mstr_symbols"
HDL_POWER"GND";
"A\NAC"3;
%"GND"
"1","(-3050,3700)","0","mstr_symbols","I31";
;
VOLTAGE"0.0V"
BODY_TYPE"PLUMBING"
CDS_LIB"mstr_symbols"
SIZE"1B"
HDL_POWER"GND";
"A\NAC"4;
%"P3V3"
"1","(-4275,4475)","0","mstr_symbols","I32";
;
HDL_POWER"P3V3"
BODY_TYPE"PLUMBING"
VOLTAGE"3.3V"
CDS_LIB"mstr_symbols"
SIZE"1B";
"G\NAC"5;
%"GND"
"1","(-4575,4025)","0","mstr_symbols","I33";
;
BODY_TYPE"PLUMBING"
VOLTAGE"0.0V"
CDS_LIB"mstr_symbols"
SIZE"1B"
HDL_POWER"GND";
"A\NAC"6;
%"CAP_A"
"1","(-4575,4225)","0","dev_discrete","I34";
;
MATERIAL"X7R"
TOLERANCE"10%"
LOCATION"C3F2"
VOLTAGE"16V"
PACK_TYPE"0402V"
VALUE"0.1UF"
PART_NUMBER"A36096-030"
CDS_LOCATION"C3F2"
CDS_LIB"dev_discrete"
ROOM"CLOCK_CPU1_OSC"
SEC_TYPE"0402V"
SEC"1"
CDS_SEC"1";
"B"
$PN"2"6;
"A"
$PN"1"5;
%"RES"
"1","(525,4325)","0","mstr_discrete","I37";
;
CDS_SEC"1"
PART_NUMBER"G21497-005"
LOCATION"R6F8"
WATTAGE"1/16W"
VALUE"0.0"
TOLERANCE"5%"
PACK_TYPE"0402"
MATERIAL"EMPTY"
ROOM"CLOCK_CPU0_OSC"
CDS_LIB"mstr_discrete"
NO_XNET_CONNECTION"1"
SEC"1"
SEC_TYPE"0402"
CDS_LOCATION"R6F8";
"B"
$PN"2"19;
"A"
$PN"1"23;
%"RES"
"1","(525,5025)","0","mstr_discrete","I41";
;
CDS_SEC"1"
WATTAGE"1/16W"
PART_NUMBER"G21497-005"
PACK_TYPE"0402"
LOCATION"R6F6"
MATERIAL"EMPTY"
TOLERANCE"5%"
VALUE"0.0"
SEC_TYPE"0402"
SEC"1"
NO_XNET_CONNECTION"1"
ROOM"CLOCK_CPU0_OSC"
CDS_LIB"mstr_discrete"
CDS_LOCATION"R6F6";
"B"
$PN"2"25;
"A"
$PN"1"24;
%"RES"
"1","(525,3625)","0","mstr_discrete","I51";
;
CDS_SEC"1"
PART_NUMBER"G21497-005"
LOCATION"R3F1"
MATERIAL"EMPTY"
WATTAGE"1/16W"
TOLERANCE"5%"
VALUE"0.0"
PACK_TYPE"0402"
ROOM"CLOCK_CPU1_OSC"
CDS_LIB"mstr_discrete"
SEC_TYPE"0402"
NO_XNET_CONNECTION"1"
SEC"1"
CDS_LOCATION"R3F1";
"B"
$PN"2"21;
"A"
$PN"1"29;
%"RES"
"1","(525,2925)","0","mstr_discrete","I53";
;
CDS_SEC"1"
PART_NUMBER"G21497-005"
PACK_TYPE"0402"
WATTAGE"1/16W"
MATERIAL"EMPTY"
TOLERANCE"5%"
LOCATION"R3F3"
VALUE"0.0"
SEC_TYPE"0402"
SEC"1"
NO_XNET_CONNECTION"1"
ROOM"CLOCK_CPU1_OSC"
CDS_LIB"mstr_discrete"
CDS_LOCATION"R3F3";
"B"
$PN"2"14;
"A"
$PN"1"30;
%"RES"
"1","(525,5175)","0","mstr_discrete","I67";
;
CDS_SEC"1"
MATERIAL"CHIP"
PACK_TYPE"0402"
PART_NUMBER"G21497-005"
TOLERANCE"5%"
VALUE"0.0"
WATTAGE"1/16W"
LOCATION"R6F7"
NO_XNET_CONNECTION"1"
ROOM"CLOCK_CPU0_OSC"
CDS_LOCATION"R6F7"
SEC"1"
SEC_TYPE"0402"
CDS_LIB"mstr_discrete";
"B"
$PN"2"25;
"A"
$PN"1"28;
%"RES"
"1","(525,4475)","0","mstr_discrete","I68";
;
CDS_SEC"1"
PART_NUMBER"G21497-005"
WATTAGE"1/16W"
VALUE"0.0"
LOCATION"R6F9"
PACK_TYPE"0402"
TOLERANCE"5%"
MATERIAL"CHIP"
CDS_LIB"mstr_discrete"
SEC_TYPE"0402"
NO_XNET_CONNECTION"1"
SEC"1"
ROOM"CLOCK_CPU0_OSC"
CDS_LOCATION"R6F9";
"B"
$PN"2"19;
"A"
$PN"1"27;
%"RES"
"1","(525,3775)","0","mstr_discrete","I69";
;
CDS_SEC"1"
PACK_TYPE"0402"
PART_NUMBER"G21497-005"
LOCATION"R3F2"
VALUE"0.0"
WATTAGE"1/16W"
MATERIAL"CHIP"
TOLERANCE"5%"
CDS_LOCATION"R3F2"
NO_XNET_CONNECTION"1"
ROOM"CLOCK_CPU1_OSC"
SEC"1"
SEC_TYPE"0402"
CDS_LIB"mstr_discrete";
"B"
$PN"2"21;
"A"
$PN"1"26;
%"RES"
"1","(525,3075)","0","mstr_discrete","I70";
;
CDS_SEC"1"
VALUE"0.0"
TOLERANCE"5%"
MATERIAL"CHIP"
LOCATION"R3F4"
PACK_TYPE"0402"
WATTAGE"1/16W"
PART_NUMBER"G21497-005"
CDS_LIB"mstr_discrete"
SEC_TYPE"0402"
SEC"1"
ROOM"CLOCK_CPU1_OSC"
NO_XNET_CONNECTION"1"
CDS_LOCATION"R3F4";
"B"
$PN"2"14;
"A"
$PN"1"35;
%"OSC_C"
"17","(-3400,4775)","0","mstr_discrete","I71";
;
CDS_SEC"1"
VALUE"156.25MHZ"
MATERIAL"OSC"
LOCATION"Y6F1"
PART_NUMBER"G63831-004"
CDS_LMAN_SYM_OUTLINE"-450,200,450,-200"
CDS_LIB"mstr_discrete"
CDS_LOCATION"Y6F1"
SEC_TYPE"6P10"
SEC"1"
PACK_TYPE"6P10";
"ENABLE_DISABLE"
$PN"1"34;
"OUT"
$PN"4"8;
"GND"
$PN"3"2;
"VCC"
$PN"6"1;
"OUT_N \B"
$PN"5"37;
"NC_GND"
$PN"2"31;
%"OSC_C"
"17","(-3700,3925)","0","mstr_discrete","I72";
;
CDS_SEC"1"
PART_NUMBER"G63831-004"
VALUE"156.25MHZ"
MATERIAL"OSC"
LOCATION"Y3F1"
SEC"1"
CDS_LOCATION"Y3F1"
SEC_TYPE"6P10"
PACK_TYPE"6P10"
CDS_LIB"mstr_discrete"
CDS_LMAN_SYM_OUTLINE"-450,200,450,-200";
"ENABLE_DISABLE"
$PN"1"33;
"OUT"
$PN"4"38;
"GND"
$PN"3"4;
"VCC"
$PN"6"5;
"OUT_N \B"
$PN"5"7;
"NC_GND"
$PN"2"32;
%"RES"
"1","(525,4825)","0","mstr_discrete","I78";
;
CDS_SEC"1"
CDS_LOCATION"R6F10"
PART_NUMBER"G21497-005"
PACK_TYPE"0402"
VALUE"0.0"
MATERIAL"EMPTY"
LOCATION"R6F10"
TOLERANCE"5%"
WATTAGE"1/16W"
CDS_LIB"mstr_discrete"
SEC_TYPE"0402"
SEC"1";
"B"
$PN"2"18;
"A"
$PN"1"24;
%"RES"
"1","(525,4125)","0","mstr_discrete","I79";
;
CDS_SEC"1"
CDS_LOCATION"R6F11"
WATTAGE"1/16W"
LOCATION"R6F11"
PART_NUMBER"G21497-005"
MATERIAL"EMPTY"
VALUE"0.0"
PACK_TYPE"0402"
TOLERANCE"5%"
CDS_LIB"mstr_discrete"
SEC_TYPE"0402"
SEC"1";
"B"
$PN"2"20;
"A"
$PN"1"23;
%"RES"
"1","(525,3425)","0","mstr_discrete","I84";
;
CDS_SEC"1"
CDS_LOCATION"R3F5"
PART_NUMBER"G21497-005"
LOCATION"R3F5"
MATERIAL"EMPTY"
PACK_TYPE"0402"
TOLERANCE"5%"
VALUE"0.0"
WATTAGE"1/16W"
CDS_LIB"mstr_discrete"
SEC_TYPE"0402"
SEC"1";
"B"
$PN"2"22;
"A"
$PN"1"29;
%"RES"
"1","(525,2725)","0","mstr_discrete","I88";
;
CDS_SEC"1"
CDS_LOCATION"R3F6"
PART_NUMBER"G21497-005"
LOCATION"R3F6"
MATERIAL"EMPTY"
TOLERANCE"5%"
WATTAGE"1/16W"
VALUE"0.0"
PACK_TYPE"0402"
CDS_LIB"mstr_discrete"
SEC_TYPE"0402"
SEC"1";
"B"
$PN"2"15;
"A"
$PN"1"30;
%"RES"
"1","(550,2200)","0","mstr_discrete","I93";
;
CDS_SEC"1"
CDS_LOCATION"R8D43"
WATTAGE"1/16W"
VALUE"0.0"
LOCATION"R8D43"
TOLERANCE"5%"
MATERIAL"CHIP"
PACK_TYPE"0402"
PART_NUMBER"G21497-005"
ROOM"CLOCK_CPU1_OSC"
SEC"1"
SEC_TYPE"0402"
CDS_LIB"mstr_discrete";
"B"
$PN"2"16;
"A"
$PN"1"17;
%"RES"
"1","(550,2000)","0","mstr_discrete","I94";
;
CDS_SEC"1"
CDS_LOCATION"R7D40"
MATERIAL"EMPTY"
LOCATION"R7D40"
TOLERANCE"5%"
PACK_TYPE"0402"
PART_NUMBER"G21497-005"
WATTAGE"1/16W"
VALUE"0.0"
CDS_LIB"mstr_discrete"
SEC"1"
SEC_TYPE"0402"
ROOM"CLOCK_CPU1_OSC";
"B"
$PN"2"16;
"A"
$PN"1"9;
%"RES"
"1","(550,1500)","0","mstr_discrete","I96";
;
CDS_SEC"1"
CDS_LOCATION"R7D36"
PART_NUMBER"G21497-005"
PACK_TYPE"0402"
VALUE"0.0"
WATTAGE"1/16W"
LOCATION"R7D36"
TOLERANCE"5%"
MATERIAL"CHIP"
ROOM"CLOCK_CPU1_OSC"
SEC"1"
SEC_TYPE"0402"
CDS_LIB"mstr_discrete";
"B"
$PN"2"11;
"A"
$PN"1"36;
%"RES"
"1","(550,1300)","0","mstr_discrete","I97";
;
CDS_SEC"1"
CDS_LOCATION"R7D38"
PACK_TYPE"0402"
MATERIAL"EMPTY"
PART_NUMBER"G21497-005"
TOLERANCE"5%"
VALUE"0.0"
WATTAGE"1/16W"
LOCATION"R7D38"
SEC"1"
SEC_TYPE"0402"
CDS_LIB"mstr_discrete"
ROOM"CLOCK_CPU1_OSC";
"B"
$PN"2"11;
"A"
$PN"1"12;
END.
